(kicad_pcb
	(version 20260206)
	(generator "pcbnew")
	(generator_version "10.0")
	(general
		(thickness 1.6)
		(legacy_teardrops no)
	)
	(paper "A4")
	(title_block
		(title "04192023_DAF0TMB3IC0_F0TG_MB_C_brd_V02_OCP.brd")
		(comment 1 "Grand Teton / footprint 3955 of 8354 (U25), pads 3003-3112 of 6102")
	)
	(layers
		(0 "F.Cu" signal "TOP")
		(4 "In1.Cu" signal "GND")
		(6 "In2.Cu" signal "IN1")
		(8 "In3.Cu" signal "GND1")
		(10 "In4.Cu" signal "IN2")
		(12 "In5.Cu" signal "GND2")
		(14 "In6.Cu" signal "IN3")
		(16 "In7.Cu" signal "GND3")
		(18 "In8.Cu" signal "VCC")
		(20 "In9.Cu" signal "VCC1")
		(22 "In10.Cu" signal "GND4")
		(24 "In11.Cu" signal "IN4")
		(26 "In12.Cu" signal "GND5")
		(28 "In13.Cu" signal "IN5")
		(30 "In14.Cu" signal "GND6")
		(32 "In15.Cu" signal "IN6")
		(34 "In16.Cu" signal "GND7")
		(2 "B.Cu" signal "BOTTOM")
		(9 "F.Adhes" user "F.Adhesive")
		(11 "B.Adhes" user "B.Adhesive")
		(13 "F.Paste" user "Package Geometry/Pastemask Top")
		(15 "B.Paste" user "Package Geometry/Pastemask Bottom")
		(5 "F.SilkS" user "Ref Des/Silkscreen Top")
		(7 "B.SilkS" user "Ref Des/Silkscreen Bottom")
		(1 "F.Mask" user "Board Geometry/Soldermask Top")
		(3 "B.Mask" user "Board Geometry/Soldermask Bottom")
		(17 "Dwgs.User" user "User.Drawings")
		(19 "Cmts.User" user "User.Comments")
		(21 "Eco1.User" user "User.Eco1")
		(23 "Eco2.User" user "User.Eco2")
		(25 "Edge.Cuts" user "Board Geometry/Outline")
		(27 "Margin" user)
		(31 "F.CrtYd" user "Package Geometry/Place Bound Top")
		(29 "B.CrtYd" user "Package Geometry/Place Bound Bottom")
		(35 "F.Fab" user "Ref Des/Assembly Top")
		(33 "B.Fab" user "Ref Des/Assembly Bottom")
	)
	(footprint ""
		(layer "F.Cu")
		(at 359.867962 -258.880102 180)
		(property "Reference" "U25"
			(at -45.78477 -62.086744 0)
			(unlocked yes)
			(layer "F.SilkS")
			(effects
				(font
					(size 0.7874 0.5842)
					(thickness 0.1524)
				)
			)
		)
		(property "Value" ""
			(at 0 0 180)
			(layer "F.Fab")
			(effects
				(font
					(size 1.27 1.27)
				)
			)
		)
		(duplicate_pad_numbers_are_jumpers no)
		(pad "CC54" smd circle
			(at 14.420088 15.750032 180)
			(size 0.450088 0.450088)
			(layers "F.Cu" "F.Mask" "F.Paste")
			(net "GND")
		)
		(pad "CC55" smd circle
			(at 15.359888 15.750032 180)
			(size 0.450088 0.450088)
			(layers "F.Cu" "F.Mask" "F.Paste")
			(net "M_C_CPU0_SB_DQ<1>")
		)
		(pad "CC56" smd circle
			(at 16.299942 15.750032 180)
			(size 0.450088 0.450088)
			(layers "F.Cu" "F.Mask" "F.Paste")
			(net "GND")
		)
		(pad "CC57" smd circle
			(at 17.239996 15.750032 180)
			(size 0.450088 0.450088)
			(layers "F.Cu" "F.Mask" "F.Paste")
			(net "M_C_CPU0_SB_DQ<2>")
		)
		(pad "CC58" smd circle
			(at 18.18005 15.750032 180)
			(size 0.450088 0.450088)
			(layers "F.Cu" "F.Mask" "F.Paste")
			(net "GND")
		)
		(pad "CC59" smd circle
			(at 19.120104 15.750032 180)
			(size 0.450088 0.450088)
			(layers "F.Cu" "F.Mask" "F.Paste")
			(net "M_D_CPU0_SB_DQ<1>")
		)
		(pad "CC60" smd circle
			(at 20.059904 15.750032 180)
			(size 0.450088 0.450088)
			(layers "F.Cu" "F.Mask" "F.Paste")
			(net "M_D_CPU0_SB_DQ<2>")
		)
		(pad "CC61" smd circle
			(at 20.999958 15.750032 180)
			(size 0.450088 0.450088)
			(layers "F.Cu" "F.Mask" "F.Paste")
			(net "GND")
		)
		(pad "CC62" smd circle
			(at 21.940012 15.750032 180)
			(size 0.450088 0.450088)
			(layers "F.Cu" "F.Mask" "F.Paste")
			(net "M_B_CPU0_SB_DQ<1>")
		)
		(pad "CC63" smd circle
			(at 22.880066 15.750032 180)
			(size 0.450088 0.450088)
			(layers "F.Cu" "F.Mask" "F.Paste")
			(net "GND")
		)
		(pad "CC64" smd circle
			(at 23.82012 15.750032 180)
			(size 0.450088 0.450088)
			(layers "F.Cu" "F.Mask" "F.Paste")
			(net "M_B_CPU0_SB_DQ<2>")
		)
		(pad "CC65" smd circle
			(at 24.75992 15.750032 180)
			(size 0.450088 0.450088)
			(layers "F.Cu" "F.Mask" "F.Paste")
			(net "GND")
		)
		(pad "CC66" smd circle
			(at 25.699974 15.750032 180)
			(size 0.450088 0.450088)
			(layers "F.Cu" "F.Mask" "F.Paste")
			(net "M_F_CPU0_SB_DQ<1>")
		)
		(pad "CC67" smd circle
			(at 26.640028 15.750032 180)
			(size 0.450088 0.450088)
			(layers "F.Cu" "F.Mask" "F.Paste")
			(net "M_F_CPU0_SB_DQ<2>")
		)
		(pad "CC68" smd circle
			(at 27.580082 15.750032 180)
			(size 0.450088 0.450088)
			(layers "F.Cu" "F.Mask" "F.Paste")
			(net "GND")
		)
		(pad "CC69" smd circle
			(at 28.519882 15.750032 180)
			(size 0.450088 0.450088)
			(layers "F.Cu" "F.Mask" "F.Paste")
			(net "M_E_CPU0_SB_DQ<1>")
		)
		(pad "CC70" smd circle
			(at 29.459936 15.750032 180)
			(size 0.450088 0.450088)
			(layers "F.Cu" "F.Mask" "F.Paste")
			(net "GND")
		)
		(pad "CC71" smd circle
			(at 30.39999 15.750032 180)
			(size 0.450088 0.450088)
			(layers "F.Cu" "F.Mask" "F.Paste")
			(net "M_E_CPU0_SB_DQ<2>")
		)
		(pad "CC72" smd circle
			(at 31.340044 15.750032 180)
			(size 0.450088 0.450088)
			(layers "F.Cu" "F.Mask" "F.Paste")
			(net "GND")
		)
		(pad "CC73" smd circle
			(at 32.280098 15.750032 180)
			(size 0.450088 0.450088)
			(layers "F.Cu" "F.Mask" "F.Paste")
			(net "M_A_CPU0_SB_DQ<1>")
		)
		(pad "CC74" smd circle
			(at 33.219898 15.750032 180)
			(size 0.450088 0.450088)
			(layers "F.Cu" "F.Mask" "F.Paste")
			(net "M_A_CPU0_SB_DQ<2>")
		)
		(pad "CC75" smd circle
			(at 34.159952 15.750032 180)
			(size 0.450088 0.450088)
			(layers "F.Cu" "F.Mask" "F.Paste")
			(net "GND")
		)
		(pad "CD2" smd circle
			(at -33.990026 16.560038 180)
			(size 0.450088 0.450088)
			(layers "F.Cu" "F.Mask" "F.Paste")
			(net "M_G_CPU0_SB_DQS_DP<0>")
		)
		(pad "CD3" smd circle
			(at -33.049972 16.560038 180)
			(size 0.450088 0.450088)
			(layers "F.Cu" "F.Mask" "F.Paste")
			(net "GND")
		)
		(pad "CD4" smd circle
			(at -32.109918 16.560038 180)
			(size 0.450088 0.450088)
			(layers "F.Cu" "F.Mask" "F.Paste")
			(net "M_G_CPU0_SB_DQ<3>")
		)
		(pad "CD5" smd circle
			(at -31.170118 16.560038 180)
			(size 0.450088 0.450088)
			(layers "F.Cu" "F.Mask" "F.Paste")
			(net "PVDD11_S3_P0")
		)
		(pad "CD6" smd circle
			(at -30.230064 16.560038 180)
			(size 0.450088 0.450088)
			(layers "F.Cu" "F.Mask" "F.Paste")
			(net "M_K_CPU0_SB_DQS_DP<0>")
		)
		(pad "CD7" smd circle
			(at -29.29001 16.560038 180)
			(size 0.450088 0.450088)
			(layers "F.Cu" "F.Mask" "F.Paste")
			(net "M_K_CPU0_SB_DQ<3>")
		)
		(pad "CD8" smd circle
			(at -28.349956 16.560038 180)
			(size 0.450088 0.450088)
			(layers "F.Cu" "F.Mask" "F.Paste")
			(net "GND")
		)
		(pad "CD9" smd circle
			(at -27.409902 16.560038 180)
			(size 0.450088 0.450088)
			(layers "F.Cu" "F.Mask" "F.Paste")
			(net "M_L_CPU0_SB_DQS_DP<0>")
		)
		(pad "CD10" smd circle
			(at -26.470102 16.560038 180)
			(size 0.450088 0.450088)
			(layers "F.Cu" "F.Mask" "F.Paste")
			(net "GND")
		)
		(pad "CD11" smd circle
			(at -25.530048 16.560038 180)
			(size 0.450088 0.450088)
			(layers "F.Cu" "F.Mask" "F.Paste")
			(net "M_L_CPU0_SB_DQ<3>")
		)
		(pad "CD12" smd circle
			(at -24.589994 16.560038 180)
			(size 0.450088 0.450088)
			(layers "F.Cu" "F.Mask" "F.Paste")
			(net "PVDD11_S3_P0")
		)
		(pad "CD13" smd circle
			(at -23.64994 16.560038 180)
			(size 0.450088 0.450088)
			(layers "F.Cu" "F.Mask" "F.Paste")
			(net "M_H_CPU0_SB_DQS_DP<0>")
		)
		(pad "CD14" smd circle
			(at -22.709886 16.560038 180)
			(size 0.450088 0.450088)
			(layers "F.Cu" "F.Mask" "F.Paste")
			(net "M_H_CPU0_SB_DQ<3>")
		)
		(pad "CD15" smd circle
			(at -21.770086 16.560038 180)
			(size 0.450088 0.450088)
			(layers "F.Cu" "F.Mask" "F.Paste")
			(net "GND")
		)
		(pad "CD16" smd circle
			(at -20.830032 16.560038 180)
			(size 0.450088 0.450088)
			(layers "F.Cu" "F.Mask" "F.Paste")
			(net "M_J_CPU0_SB_DQS_DP<0>")
		)
		(pad "CD17" smd circle
			(at -19.889978 16.560038 180)
			(size 0.450088 0.450088)
			(layers "F.Cu" "F.Mask" "F.Paste")
			(net "GND")
		)
		(pad "CD18" smd circle
			(at -18.949924 16.560038 180)
			(size 0.450088 0.450088)
			(layers "F.Cu" "F.Mask" "F.Paste")
			(net "M_J_CPU0_SB_DQ<3>")
		)
		(pad "CD19" smd circle
			(at -18.010124 16.560038 180)
			(size 0.450088 0.450088)
			(layers "F.Cu" "F.Mask" "F.Paste")
			(net "PVDD11_S3_P0")
		)
		(pad "CD20" smd circle
			(at -17.07007 16.560038 180)
			(size 0.450088 0.450088)
			(layers "F.Cu" "F.Mask" "F.Paste")
			(net "M_I_CPU0_SB_DQS_DP<0>")
		)
		(pad "CD21" smd circle
			(at -16.130016 16.560038 180)
			(size 0.450088 0.450088)
			(layers "F.Cu" "F.Mask" "F.Paste")
			(net "M_I_CPU0_SB_DQ<3>")
		)
		(pad "CD22" smd circle
			(at -15.189962 16.560038 180)
			(size 0.450088 0.450088)
			(layers "F.Cu" "F.Mask" "F.Paste")
			(net "GND")
		)
		(pad "CD23" smd circle
			(at -14.249908 16.560038 180)
			(size 0.450088 0.450088)
			(layers "F.Cu" "F.Mask" "F.Paste")
			(net "PVDDCR_CPU1_P0")
		)
		(pad "CD24" smd circle
			(at -13.310108 16.560038 180)
			(size 0.450088 0.450088)
			(layers "F.Cu" "F.Mask" "F.Paste")
			(net "PVDDCR_CPU1_P0")
		)
		(pad "CD25" smd circle
			(at -12.370054 16.560038 180)
			(size 0.450088 0.450088)
			(layers "F.Cu" "F.Mask" "F.Paste")
			(net "GND")
		)
		(pad "CD26" smd circle
			(at -11.43 16.560038 180)
			(size 0.450088 0.450088)
			(layers "F.Cu" "F.Mask" "F.Paste")
			(net "PVDDCR_CPU1_P0")
		)
		(pad "CD27" smd circle
			(at -10.489946 16.560038 180)
			(size 0.450088 0.450088)
			(layers "F.Cu" "F.Mask" "F.Paste")
			(net "PVDDCR_CPU1_P0")
		)
		(pad "CD28" smd circle
			(at -9.549892 16.560038 180)
			(size 0.450088 0.450088)
			(layers "F.Cu" "F.Mask" "F.Paste")
			(net "GND")
		)
		(pad "CD29" smd circle
			(at -8.610092 16.560038 180)
			(size 0.450088 0.450088)
			(layers "F.Cu" "F.Mask" "F.Paste")
			(net "PVDDCR_CPU1_P0")
		)
		(pad "CD30" smd circle
			(at -7.670038 16.560038 180)
			(size 0.450088 0.450088)
			(layers "F.Cu" "F.Mask" "F.Paste")
			(net "PVDDCR_CPU1_P0")
		)
		(pad "CD31" smd circle
			(at -6.729984 16.560038 180)
			(size 0.450088 0.450088)
			(layers "F.Cu" "F.Mask" "F.Paste")
			(net "GND")
		)
		(pad "CD32" smd circle
			(at -5.78993 16.560038 180)
			(size 0.450088 0.450088)
			(layers "F.Cu" "F.Mask" "F.Paste")
			(net "PVDDCR_CPU1_P0")
		)
		(pad "CD33" smd circle
			(at -4.849876 16.560038 180)
			(size 0.450088 0.450088)
			(layers "F.Cu" "F.Mask" "F.Paste")
			(net "PVDDCR_CPU1_P0")
		)
		(pad "CD34" smd circle
			(at -3.910076 16.560038 180)
			(size 0.450088 0.450088)
			(layers "F.Cu" "F.Mask" "F.Paste")
			(net "GND")
		)
		(pad "CD35" smd circle
			(at -2.970022 16.560038 180)
			(size 0.450088 0.450088)
			(layers "F.Cu" "F.Mask" "F.Paste")
			(net "P5E_CPU0_P3_TX_DN<0>")
		)
		(pad "CD36" smd circle
			(at -2.029968 16.560038 180)
			(size 0.450088 0.450088)
			(layers "F.Cu" "F.Mask" "F.Paste")
			(net "P5E_CPU0_P3_TX_DP<0>")
		)
		(pad "CD37" smd circle
			(at -1.089914 16.560038 180)
			(size 0.450088 0.450088)
			(layers "F.Cu" "F.Mask" "F.Paste")
			(net "GND")
		)
		(pad "CD39" smd circle
			(at 0.78994 16.560038 180)
			(size 0.450088 0.450088)
			(layers "F.Cu" "F.Mask" "F.Paste")
			(net "GND")
		)
		(pad "CD40" smd circle
			(at 1.729994 16.560038 180)
			(size 0.450088 0.450088)
			(layers "F.Cu" "F.Mask" "F.Paste")
			(net "P5E_CPU0_P1_RX_DP<15>")
		)
		(pad "CD41" smd circle
			(at 2.670048 16.560038 180)
			(size 0.450088 0.450088)
			(layers "F.Cu" "F.Mask" "F.Paste")
			(net "P5E_CPU0_P1_RX_DN<15>")
		)
		(pad "CD42" smd circle
			(at 3.610102 16.560038 180)
			(size 0.450088 0.450088)
			(layers "F.Cu" "F.Mask" "F.Paste")
			(net "GND")
		)
		(pad "CD43" smd circle
			(at 4.549902 16.560038 180)
			(size 0.450088 0.450088)
			(layers "F.Cu" "F.Mask" "F.Paste")
			(net "PVDDCR_CPU1_P0")
		)
		(pad "CD44" smd circle
			(at 5.489956 16.560038 180)
			(size 0.450088 0.450088)
			(layers "F.Cu" "F.Mask" "F.Paste")
			(net "PVDDCR_CPU1_P0")
		)
		(pad "CD45" smd circle
			(at 6.43001 16.560038 180)
			(size 0.450088 0.450088)
			(layers "F.Cu" "F.Mask" "F.Paste")
			(net "GND")
		)
		(pad "CD46" smd circle
			(at 7.370064 16.560038 180)
			(size 0.450088 0.450088)
			(layers "F.Cu" "F.Mask" "F.Paste")
			(net "PVDDCR_CPU1_P0")
		)
		(pad "CD47" smd circle
			(at 8.310118 16.560038 180)
			(size 0.450088 0.450088)
			(layers "F.Cu" "F.Mask" "F.Paste")
			(net "PVDDCR_CPU1_P0")
		)
		(pad "CD48" smd circle
			(at 9.249918 16.560038 180)
			(size 0.450088 0.450088)
			(layers "F.Cu" "F.Mask" "F.Paste")
			(net "GND")
		)
		(pad "CD49" smd circle
			(at 10.189972 16.560038 180)
			(size 0.450088 0.450088)
			(layers "F.Cu" "F.Mask" "F.Paste")
			(net "PVDDCR_CPU1_P0")
		)
		(pad "CD50" smd circle
			(at 11.130026 16.560038 180)
			(size 0.450088 0.450088)
			(layers "F.Cu" "F.Mask" "F.Paste")
			(net "PVDDCR_CPU1_P0")
		)
		(pad "CD51" smd circle
			(at 12.07008 16.560038 180)
			(size 0.450088 0.450088)
			(layers "F.Cu" "F.Mask" "F.Paste")
			(net "GND")
		)
		(pad "CD52" smd circle
			(at 13.00988 16.560038 180)
			(size 0.450088 0.450088)
			(layers "F.Cu" "F.Mask" "F.Paste")
			(net "PVDDCR_CPU1_P0")
		)
		(pad "CD53" smd circle
			(at 13.949934 16.560038 180)
			(size 0.450088 0.450088)
			(layers "F.Cu" "F.Mask" "F.Paste")
			(net "PVDDCR_CPU1_P0")
		)
		(pad "CD54" smd circle
			(at 14.889988 16.560038 180)
			(size 0.450088 0.450088)
			(layers "F.Cu" "F.Mask" "F.Paste")
			(net "GND")
		)
		(pad "CD55" smd circle
			(at 15.830042 16.560038 180)
			(size 0.450088 0.450088)
			(layers "F.Cu" "F.Mask" "F.Paste")
			(net "M_C_CPU0_SB_DQ<3>")
		)
		(pad "CD56" smd circle
			(at 16.770096 16.560038 180)
			(size 0.450088 0.450088)
			(layers "F.Cu" "F.Mask" "F.Paste")
			(net "M_C_CPU0_SB_DQS_DP<0>")
		)
		(pad "CD57" smd circle
			(at 17.709896 16.560038 180)
			(size 0.450088 0.450088)
			(layers "F.Cu" "F.Mask" "F.Paste")
			(net "PVDDIO_P0")
		)
		(pad "CD58" smd circle
			(at 18.64995 16.560038 180)
			(size 0.450088 0.450088)
			(layers "F.Cu" "F.Mask" "F.Paste")
			(net "M_D_CPU0_SB_DQ<3>")
		)
		(pad "CD59" smd circle
			(at 19.590004 16.560038 180)
			(size 0.450088 0.450088)
			(layers "F.Cu" "F.Mask" "F.Paste")
			(net "GND")
		)
		(pad "CD60" smd circle
			(at 20.530058 16.560038 180)
			(size 0.450088 0.450088)
			(layers "F.Cu" "F.Mask" "F.Paste")
			(net "M_D_CPU0_SB_DQS_DP<0>")
		)
		(pad "CD61" smd circle
			(at 21.470112 16.560038 180)
			(size 0.450088 0.450088)
			(layers "F.Cu" "F.Mask" "F.Paste")
			(net "GND")
		)
		(pad "CD62" smd circle
			(at 22.409912 16.560038 180)
			(size 0.450088 0.450088)
			(layers "F.Cu" "F.Mask" "F.Paste")
			(net "M_B_CPU0_SB_DQ<3>")
		)
		(pad "CD63" smd circle
			(at 23.349966 16.560038 180)
			(size 0.450088 0.450088)
			(layers "F.Cu" "F.Mask" "F.Paste")
			(net "M_B_CPU0_SB_DQS_DP<0>")
		)
		(pad "CD64" smd circle
			(at 24.29002 16.560038 180)
			(size 0.450088 0.450088)
			(layers "F.Cu" "F.Mask" "F.Paste")
			(net "PVDDIO_P0")
		)
		(pad "CD65" smd circle
			(at 25.230074 16.560038 180)
			(size 0.450088 0.450088)
			(layers "F.Cu" "F.Mask" "F.Paste")
			(net "M_F_CPU0_SB_DQ<3>")
		)
		(pad "CD66" smd circle
			(at 26.170128 16.560038 180)
			(size 0.450088 0.450088)
			(layers "F.Cu" "F.Mask" "F.Paste")
			(net "GND")
		)
		(pad "CD67" smd circle
			(at 27.109928 16.560038 180)
			(size 0.450088 0.450088)
			(layers "F.Cu" "F.Mask" "F.Paste")
			(net "M_F_CPU0_SB_DQS_DP<0>")
		)
		(pad "CD68" smd circle
			(at 28.049982 16.560038 180)
			(size 0.450088 0.450088)
			(layers "F.Cu" "F.Mask" "F.Paste")
			(net "GND")
		)
		(pad "CD69" smd circle
			(at 28.990036 16.560038 180)
			(size 0.450088 0.450088)
			(layers "F.Cu" "F.Mask" "F.Paste")
			(net "M_E_CPU0_SB_DQ<3>")
		)
		(pad "CD70" smd circle
			(at 29.93009 16.560038 180)
			(size 0.450088 0.450088)
			(layers "F.Cu" "F.Mask" "F.Paste")
			(net "M_E_CPU0_SB_DQS_DP<0>")
		)
		(pad "CD71" smd circle
			(at 30.86989 16.560038 180)
			(size 0.450088 0.450088)
			(layers "F.Cu" "F.Mask" "F.Paste")
			(net "PVDDIO_P0")
		)
		(pad "CD72" smd circle
			(at 31.809944 16.560038 180)
			(size 0.450088 0.450088)
			(layers "F.Cu" "F.Mask" "F.Paste")
			(net "M_A_CPU0_SB_DQ<3>")
		)
		(pad "CD73" smd circle
			(at 32.749998 16.560038 180)
			(size 0.450088 0.450088)
			(layers "F.Cu" "F.Mask" "F.Paste")
			(net "GND")
		)
		(pad "CD74" smd circle
			(at 33.690052 16.560038 180)
			(size 0.450088 0.450088)
			(layers "F.Cu" "F.Mask" "F.Paste")
			(net "M_A_CPU0_SB_DQS_DP<0>")
		)
		(pad "CE1" smd circle
			(at -34.459926 17.370044 180)
			(size 0.450088 0.450088)
			(layers "F.Cu" "F.Mask" "F.Paste")
			(net "GND")
		)
		(pad "CE2" smd circle
			(at -33.519872 17.370044 180)
			(size 0.450088 0.450088)
			(layers "F.Cu" "F.Mask" "F.Paste")
			(net "M_G_CPU0_SB_DQS_DN<0>")
		)
		(pad "CE3" smd circle
			(at -32.580072 17.370044 180)
			(size 0.450088 0.450088)
			(layers "F.Cu" "F.Mask" "F.Paste")
			(net "M_G_CPU0_SB_DQS_DN<5>")
		)
		(pad "CE4" smd circle
			(at -31.640018 17.370044 180)
			(size 0.450088 0.450088)
			(layers "F.Cu" "F.Mask" "F.Paste")
			(net "GND")
		)
		(pad "CE5" smd circle
			(at -30.699964 17.370044 180)
			(size 0.450088 0.450088)
			(layers "F.Cu" "F.Mask" "F.Paste")
			(net "M_K_CPU0_SB_DQS_DN<0>")
		)
		(pad "CE6" smd circle
			(at -29.75991 17.370044 180)
			(size 0.450088 0.450088)
			(layers "F.Cu" "F.Mask" "F.Paste")
			(net "GND")
		)
		(pad "CE7" smd circle
			(at -28.82011 17.370044 180)
			(size 0.450088 0.450088)
			(layers "F.Cu" "F.Mask" "F.Paste")
			(net "M_K_CPU0_SB_DQS_DN<5>")
		)
		(pad "CE8" smd circle
			(at -27.880056 17.370044 180)
			(size 0.450088 0.450088)
			(layers "F.Cu" "F.Mask" "F.Paste")
			(net "GND")
		)
		(pad "CE9" smd circle
			(at -26.940002 17.370044 180)
			(size 0.450088 0.450088)
			(layers "F.Cu" "F.Mask" "F.Paste")
			(net "M_L_CPU0_SB_DQS_DN<0>")
		)
		(pad "CE10" smd circle
			(at -25.999948 17.370044 180)
			(size 0.450088 0.450088)
			(layers "F.Cu" "F.Mask" "F.Paste")
			(net "M_L_CPU0_SB_DQS_DN<5>")
		)
		(pad "CE11" smd circle
			(at -25.059894 17.370044 180)
			(size 0.450088 0.450088)
			(layers "F.Cu" "F.Mask" "F.Paste")
			(net "GND")
		)
		(pad "CE12" smd circle
			(at -24.120094 17.370044 180)
			(size 0.450088 0.450088)
			(layers "F.Cu" "F.Mask" "F.Paste")
			(net "M_H_CPU0_SB_DQS_DN<0>")
		)
		(pad "CE13" smd circle
			(at -23.18004 17.370044 180)
			(size 0.450088 0.450088)
			(layers "F.Cu" "F.Mask" "F.Paste")
			(net "GND")
		)
		(pad "CE14" smd circle
			(at -22.239986 17.370044 180)
			(size 0.450088 0.450088)
			(layers "F.Cu" "F.Mask" "F.Paste")
			(net "M_H_CPU0_SB_DQS_DN<5>")
		)
		(pad "CE15" smd circle
			(at -21.299932 17.370044 180)
			(size 0.450088 0.450088)
			(layers "F.Cu" "F.Mask" "F.Paste")
			(net "GND")
		)
		(pad "CE16" smd circle
			(at -20.359878 17.370044 180)
			(size 0.450088 0.450088)
			(layers "F.Cu" "F.Mask" "F.Paste")
			(net "M_J_CPU0_SB_DQS_DN<0>")
		)
	)
)
